(kicad_pcb
	(version 20260206)
	(generator "pcbnew")
	(generator_version "10.0")
	(general
		(thickness 1.6)
		(legacy_teardrops no)
	)
	(paper "A4")
	(title_block
		(title "Bryce Canyon_R.DPB_16317-1_OCP.brd")
		(comment 1 "Bryce Canyon / footprints 1527-1533 of 2099")
	)
	(layers
		(0 "F.Cu" signal "TOP")
		(4 "In1.Cu" signal "L2GND")
		(6 "In2.Cu" signal "L3")
		(8 "In3.Cu" signal "L4VCC")
		(10 "In4.Cu" signal "L5VCC")
		(12 "In5.Cu" signal "L6")
		(14 "In6.Cu" signal "L7GND")
		(2 "B.Cu" signal "BOTTOM")
		(9 "F.Adhes" user "F.Adhesive")
		(11 "B.Adhes" user "B.Adhesive")
		(13 "F.Paste" user "Package Geometry/Pastemask Top")
		(15 "B.Paste" user "Package Geometry/Pastemask Bottom")
		(5 "F.SilkS" user "Ref Des/Silkscreen Top")
		(7 "B.SilkS" user "Ref Des/Silkscreen Bottom")
		(1 "F.Mask" user "Board Geometry/Soldermask Top")
		(3 "B.Mask" user "Board Geometry/Soldermask Bottom")
		(17 "Dwgs.User" user "User.Drawings")
		(19 "Cmts.User" user "User.Comments")
		(21 "Eco1.User" user "User.Eco1")
		(23 "Eco2.User" user "User.Eco2")
		(25 "Edge.Cuts" user "Board Geometry/Outline")
		(27 "Margin" user)
		(31 "F.CrtYd" user "Package Geometry/Place Bound Top")
		(29 "B.CrtYd" user "Package Geometry/Place Bound Bottom")
		(35 "F.Fab" user "Ref Des/Assembly Top")
		(33 "B.Fab" user "Ref Des/Assembly Bottom")
	)
	(footprint ""
		(layer "F.Cu")
		(at 242.63858 -221.52102)
		(property "Reference" "U10"
			(at 0 0 0)
			(layer "F.SilkS")
			(hide yes)
			(effects
				(font
					(size 1.27 1.27)
				)
			)
		)
		(property "Value" "PCA9557PWR-1-GP-U"
			(at 0.127 -12.573 0)
			(unlocked yes)
			(layer "F.Fab")
			(hide yes)
			(effects
				(font
					(size 1.016 1.016)
					(thickness 0.1524)
				)
			)
		)
		(property "Device Type" "TSOIC16H48"
			(at 0.1016 -14.5796 0)
			(unlocked yes)
			(layer "F.Fab")
			(hide yes)
			(effects
				(font
					(size 1.016 1.016)
					(thickness 0.1524)
				)
			)
		)
		(duplicate_pad_numbers_are_jumpers no)
		(fp_line
			(start -3.0988 -1.778)
			(end -3.0988 1.778)
			(stroke
				(width 0.1524)
				(type default)
			)
			(layer "F.SilkS")
		)
		(fp_line
			(start -3.0988 -1.778)
			(end 2.3622 -1.778)
			(stroke
				(width 0.1524)
				(type default)
			)
			(layer "F.SilkS")
		)
		(fp_line
			(start -2.921 3.81)
			(end -2.921 1.778)
			(stroke
				(width 0.508)
				(type default)
			)
			(layer "F.SilkS")
		)
		(fp_line
			(start -2.54 0)
			(end -3.0988 -0.5588)
			(stroke
				(width 0.1524)
				(type default)
			)
			(layer "F.SilkS")
		)
		(fp_line
			(start -2.54 0)
			(end -3.0988 0.5588)
			(stroke
				(width 0.1524)
				(type default)
			)
			(layer "F.SilkS")
		)
		(fp_line
			(start 2.3622 -1.778)
			(end 2.3622 1.778)
			(stroke
				(width 0.1524)
				(type default)
			)
			(layer "F.SilkS")
		)
		(fp_line
			(start 2.3622 1.778)
			(end -2.921 1.778)
			(stroke
				(width 0.1524)
				(type default)
			)
			(layer "F.SilkS")
		)
		(fp_poly
			(pts
				(xy -2.4638 -1.778) (xy -2.4638 1.778) (xy 2.3622 1.778) (xy 2.3622 -1.778)
			)
			(stroke
				(width 0)
				(type default)
			)
			(fill yes)
			(layer "F.SilkS")
		)
		(fp_rect
			(start -3.175 4.064)
			(end 3.175 -4.064)
			(stroke
				(width 0)
				(type default)
			)
			(fill no)
			(layer "F.CrtYd")
		)
		(fp_poly
			(pts
				(xy -3.175 -4.064) (xy 3.175 -4.064) (xy 3.175 4.064) (xy -3.175 4.064)
			)
			(stroke
				(width 0)
				(type default)
			)
			(fill no)
			(layer "F.Fab")
		)
		(pad "1" smd rect
			(at -2.27584 2.8194)
			(size 0.3556 1.524)
			(layers "F.Cu" "F.Mask" "F.Paste")
			(net "IO_EXP3_SCL")
		)
		(pad "2" smd rect
			(at -1.6256 2.8194)
			(size 0.3556 1.524)
			(layers "F.Cu" "F.Mask" "F.Paste")
			(net "IO_EXP3_SDA")
		)
		(pad "3" smd rect
			(at -0.97536 2.8194)
			(size 0.3556 1.524)
			(layers "F.Cu" "F.Mask" "F.Paste")
			(net "IO_EXP3_A0")
		)
		(pad "4" smd rect
			(at -0.32512 2.8194)
			(size 0.3556 1.524)
			(layers "F.Cu" "F.Mask" "F.Paste")
			(net "IO_EXP3_A1")
		)
		(pad "5" smd rect
			(at 0.32512 2.8194)
			(size 0.3556 1.524)
			(layers "F.Cu" "F.Mask" "F.Paste")
			(net "IO_EXP3_A2")
		)
		(pad "6" smd rect
			(at 0.97536 2.8194)
			(size 0.3556 1.524)
			(layers "F.Cu" "F.Mask" "F.Paste")
			(net "Net_5")
		)
		(pad "7" smd rect
			(at 1.6256 2.8194)
			(size 0.3556 1.524)
			(layers "F.Cu" "F.Mask" "F.Paste")
			(net "DRIVE_B_32_PWR")
		)
		(pad "8" smd rect
			(at 2.27584 2.8194)
			(size 0.3556 1.524)
			(layers "F.Cu" "F.Mask" "F.Paste")
			(net "GND")
		)
		(pad "9" smd rect
			(at 2.27584 -2.8194)
			(size 0.3556 1.524)
			(layers "F.Cu" "F.Mask" "F.Paste")
			(net "DRIVE_B_33_PWR")
		)
		(pad "10" smd rect
			(at 1.6256 -2.8194)
			(size 0.3556 1.524)
			(layers "F.Cu" "F.Mask" "F.Paste")
			(net "DRIVE_B_34_PWR")
		)
		(pad "11" smd rect
			(at 0.97536 -2.8194)
			(size 0.3556 1.524)
			(layers "F.Cu" "F.Mask" "F.Paste")
			(net "DRIVE_B_35_PWR")
		)
		(pad "12" smd rect
			(at 0.32512 -2.8194)
			(size 0.3556 1.524)
			(layers "F.Cu" "F.Mask" "F.Paste")
			(net "Net_984")
		)
		(pad "13" smd rect
			(at -0.32512 -2.8194)
			(size 0.3556 1.524)
			(layers "F.Cu" "F.Mask" "F.Paste")
			(net "Net_207")
		)
		(pad "14" smd rect
			(at -0.97536 -2.8194)
			(size 0.3556 1.524)
			(layers "F.Cu" "F.Mask" "F.Paste")
			(net "Net_202")
		)
		(pad "15" smd rect
			(at -1.6256 -2.8194)
			(size 0.3556 1.524)
			(layers "F.Cu" "F.Mask" "F.Paste")
			(net "IO_EXP3_RESET#")
		)
		(pad "16" smd rect
			(at -2.27584 -2.8194)
			(size 0.3556 1.524)
			(layers "F.Cu" "F.Mask" "F.Paste")
			(net "GPIO_VCC_U10")
		)
	)
	(footprint ""
		(layer "F.Cu")
		(at 37.1602 -6.4008 -90)
		(property "Reference" "C27"
			(at 0 0 270)
			(layer "F.SilkS")
			(hide yes)
			(effects
				(font
					(size 1.27 1.27)
				)
			)
		)
		(property "Value" "SCD1U16V2KX-3GP"
			(at 1.1811 -2.7051 270)
			(unlocked yes)
			(layer "F.Fab")
			(hide yes)
			(effects
				(font
					(size 1.016 1.016)
					(thickness 0.1524)
				)
			)
		)
		(property "Device Type" "C402H22"
			(at 1.1811 -4.2291 270)
			(unlocked yes)
			(layer "F.Fab")
			(hide yes)
			(effects
				(font
					(size 1.016 1.016)
					(thickness 0.1524)
				)
			)
		)
		(duplicate_pad_numbers_are_jumpers no)
		(fp_rect
			(start -0.4318 0.9525)
			(end 0.4318 -0.9525)
			(stroke
				(width 0)
				(type default)
			)
			(fill no)
			(layer "F.CrtYd")
		)
		(fp_rect
			(start -0.4318 0.9525)
			(end 0.4318 -0.9525)
			(stroke
				(width 0)
				(type default)
			)
			(fill no)
			(layer "F.Fab")
		)
		(pad "1" smd custom
			(at 0 -0.4445 270)
			(size 0.1524 0.1524)
			(layers "F.Cu" "F.Mask" "F.Paste")
			(net "GND")
			(options
				(clearance outline)
				(anchor circle)
			)
			(primitives
				(gr_poly
					(pts
						(arc
							(start 0.3048 -0.2032)
							(mid 0.275042 -0.275042)
							(end 0.2032 -0.3048)
						)
						(arc
							(start -0.2032 -0.3048)
							(mid -0.275042 -0.275042)
							(end -0.3048 -0.2032)
						)
						(arc
							(start -0.3048 0.2032)
							(mid -0.275042 0.275042)
							(end -0.2032 0.3048)
						)
						(arc
							(start 0.2032 0.3048)
							(mid 0.275042 0.275042)
							(end 0.3048 0.2032)
						)
					)
					(width 0)
					(fill yes)
				)
			)
		)
		(pad "2" smd custom
			(at 0 0.4445 270)
			(size 0.1524 0.1524)
			(layers "F.Cu" "F.Mask" "F.Paste")
			(net "P3V3_STBY_A")
			(options
				(clearance outline)
				(anchor circle)
			)
			(primitives
				(gr_poly
					(pts
						(arc
							(start 0.3048 -0.2032)
							(mid 0.275042 -0.275042)
							(end 0.2032 -0.3048)
						)
						(arc
							(start -0.2032 -0.3048)
							(mid -0.275042 -0.275042)
							(end -0.3048 -0.2032)
						)
						(arc
							(start -0.3048 0.2032)
							(mid -0.275042 0.275042)
							(end -0.2032 0.3048)
						)
						(arc
							(start 0.2032 0.3048)
							(mid 0.275042 0.275042)
							(end 0.3048 0.2032)
						)
					)
					(width 0)
					(fill yes)
				)
			)
		)
	)
	(footprint ""
		(layer "F.Cu")
		(at 190.5 -33.147 -90)
		(property "Reference" "R737"
			(at 0 0 270)
			(layer "F.SilkS")
			(hide yes)
			(effects
				(font
					(size 1.27 1.27)
				)
			)
		)
		(property "Value" "10KR2F-2-GP"
			(at 0.064008 -3.993896 270)
			(unlocked yes)
			(layer "F.Fab")
			(hide yes)
			(effects
				(font
					(size 1.016 1.016)
					(thickness 0.1524)
				)
			)
		)
		(property "Device Type" "R402H16"
			(at 0.064008 -5.517896 270)
			(unlocked yes)
			(layer "F.Fab")
			(hide yes)
			(effects
				(font
					(size 1.016 1.016)
					(thickness 0.1524)
				)
			)
		)
		(duplicate_pad_numbers_are_jumpers no)
		(fp_line
			(start -0.508 -0.9398)
			(end -0.508 0.9398)
			(stroke
				(width 0.1524)
				(type default)
			)
			(layer "F.SilkS")
		)
		(fp_line
			(start 0.508 -0.9398)
			(end -0.508 -0.9398)
			(stroke
				(width 0.1524)
				(type default)
			)
			(layer "F.SilkS")
		)
		(fp_rect
			(start -0.508 0.9398)
			(end 0.508 -0.9398)
			(stroke
				(width 0)
				(type default)
			)
			(fill no)
			(layer "F.CrtYd")
		)
		(fp_rect
			(start -0.508 0.9398)
			(end 0.508 -0.9398)
			(stroke
				(width 0)
				(type default)
			)
			(fill no)
			(layer "F.Fab")
		)
		(pad "1" smd custom
			(at 0 -0.4445 270)
			(size 0.1397 0.1397)
			(layers "F.Cu" "F.Mask" "F.Paste")
			(net "P3V3_STBY_B")
			(options
				(clearance outline)
				(anchor circle)
			)
			(primitives
				(gr_poly
					(pts
						(arc
							(start -0.1778 -0.2794)
							(mid -0.249642 -0.249642)
							(end -0.2794 -0.1778)
						)
						(arc
							(start -0.2794 0.1778)
							(mid -0.249642 0.249642)
							(end -0.1778 0.2794)
						)
						(arc
							(start 0.1778 0.2794)
							(mid 0.249642 0.249642)
							(end 0.2794 0.1778)
						)
						(arc
							(start 0.2794 -0.1778)
							(mid 0.249642 -0.249642)
							(end 0.1778 -0.2794)
						)
					)
					(width 0)
					(fill yes)
				)
			)
		)
		(pad "2" smd custom
			(at 0 0.4445 270)
			(size 0.1397 0.1397)
			(layers "F.Cu" "F.Mask" "F.Paste")
			(net "HDD_PRSNT_29")
			(options
				(clearance outline)
				(anchor circle)
			)
			(primitives
				(gr_poly
					(pts
						(arc
							(start -0.1778 -0.2794)
							(mid -0.249642 -0.249642)
							(end -0.2794 -0.1778)
						)
						(arc
							(start -0.2794 0.1778)
							(mid -0.249642 0.249642)
							(end -0.1778 0.2794)
						)
						(arc
							(start 0.1778 0.2794)
							(mid 0.249642 0.249642)
							(end 0.2794 0.1778)
						)
						(arc
							(start 0.2794 -0.1778)
							(mid 0.249642 -0.249642)
							(end 0.1778 -0.2794)
						)
					)
					(width 0)
					(fill yes)
				)
			)
		)
	)
	(footprint ""
		(layer "F.Cu")
		(at 34.763964 -154.70505)
		(property "Reference" "TP81"
			(at 0 0 0)
			(layer "F.SilkS")
			(hide yes)
			(effects
				(font
					(size 1.27 1.27)
				)
			)
		)
		(property "Value" "*"
			(at -0.0508 -1.6764 0)
			(unlocked yes)
			(layer "F.Fab")
			(hide yes)
			(effects
				(font
					(size 1.016 1.016)
					(thickness 0.1524)
				)
			)
		)
		(property "Device Type" "TPAD32"
			(at -0.0508 -3.2004 0)
			(unlocked yes)
			(layer "F.Fab")
			(hide yes)
			(effects
				(font
					(size 1.016 1.016)
					(thickness 0.1524)
				)
			)
		)
		(duplicate_pad_numbers_are_jumpers no)
		(fp_poly
			(pts
				(arc
					(start 0.4064 0)
					(mid -0.4064 0)
					(end 0.4064 0)
				)
			)
			(stroke
				(width 0)
				(type default)
			)
			(fill no)
			(layer "F.CrtYd")
		)
		(fp_poly
			(pts
				(arc
					(start 0.7112 0)
					(mid -0.7112 0)
					(end 0.7112 0)
				)
			)
			(stroke
				(width 0)
				(type default)
			)
			(fill no)
			(layer "F.Fab")
		)
		(pad "1" smd circle
			(at 0 0)
			(size 0.8128 0.8128)
			(layers "F.Cu" "F.Mask" "F.Paste")
			(net "ACT_HDD_12")
		)
	)
	(footprint ""
		(layer "F.Cu")
		(at 22.987 -19.558 90)
		(property "Reference" "R635"
			(at 0 0 90)
			(layer "F.SilkS")
			(hide yes)
			(effects
				(font
					(size 1.27 1.27)
				)
			)
		)
		(property "Value" "4K7R2F-GP"
			(at 0.064008 -3.993896 90)
			(unlocked yes)
			(layer "F.Fab")
			(hide yes)
			(effects
				(font
					(size 1.016 1.016)
					(thickness 0.1524)
				)
			)
		)
		(property "Device Type" "R402H16"
			(at 0.064008 -5.517896 90)
			(unlocked yes)
			(layer "F.Fab")
			(hide yes)
			(effects
				(font
					(size 1.016 1.016)
					(thickness 0.1524)
				)
			)
		)
		(duplicate_pad_numbers_are_jumpers no)
		(fp_line
			(start 0.508 -0.9398)
			(end -0.508 -0.9398)
			(stroke
				(width 0.1524)
				(type default)
			)
			(layer "F.SilkS")
		)
		(fp_line
			(start -0.508 -0.9398)
			(end -0.508 0.9398)
			(stroke
				(width 0.1524)
				(type default)
			)
			(layer "F.SilkS")
		)
		(fp_rect
			(start -0.508 0.9398)
			(end 0.508 -0.9398)
			(stroke
				(width 0)
				(type default)
			)
			(fill no)
			(layer "F.CrtYd")
		)
		(fp_rect
			(start -0.508 0.9398)
			(end 0.508 -0.9398)
			(stroke
				(width 0)
				(type default)
			)
			(fill no)
			(layer "F.Fab")
		)
		(pad "1" smd custom
			(at 0 -0.4445 90)
			(size 0.1397 0.1397)
			(layers "F.Cu" "F.Mask" "F.Paste")
			(net "SW_PWR_R_HDD24")
			(options
				(clearance outline)
				(anchor circle)
			)
			(primitives
				(gr_poly
					(pts
						(arc
							(start -0.1778 -0.2794)
							(mid -0.249642 -0.249642)
							(end -0.2794 -0.1778)
						)
						(arc
							(start -0.2794 0.1778)
							(mid -0.249642 0.249642)
							(end -0.1778 0.2794)
						)
						(arc
							(start 0.1778 0.2794)
							(mid 0.249642 0.249642)
							(end 0.2794 0.1778)
						)
						(arc
							(start 0.2794 -0.1778)
							(mid 0.249642 -0.249642)
							(end 0.1778 -0.2794)
						)
					)
					(width 0)
					(fill yes)
				)
			)
		)
		(pad "2" smd custom
			(at 0 0.4445 90)
			(size 0.1397 0.1397)
			(layers "F.Cu" "F.Mask" "F.Paste")
			(net "GND")
			(options
				(clearance outline)
				(anchor circle)
			)
			(primitives
				(gr_poly
					(pts
						(arc
							(start -0.1778 -0.2794)
							(mid -0.249642 -0.249642)
							(end -0.2794 -0.1778)
						)
						(arc
							(start -0.2794 0.1778)
							(mid -0.249642 0.249642)
							(end -0.1778 0.2794)
						)
						(arc
							(start 0.1778 0.2794)
							(mid 0.249642 0.249642)
							(end 0.2794 0.1778)
						)
						(arc
							(start 0.2794 -0.1778)
							(mid 0.249642 -0.249642)
							(end 0.1778 -0.2794)
						)
					)
					(width 0)
					(fill yes)
				)
			)
		)
	)
	(footprint ""
		(layer "F.Cu")
		(at 256.413 -283.845 90)
		(property "Reference" "R1178"
			(at 0 0 90)
			(layer "F.SilkS")
			(hide yes)
			(effects
				(font
					(size 1.27 1.27)
				)
			)
		)
		(property "Value" "0R2J-2-GP"
			(at 0.064008 -3.993896 90)
			(unlocked yes)
			(layer "F.Fab")
			(hide yes)
			(effects
				(font
					(size 1.016 1.016)
					(thickness 0.1524)
				)
			)
		)
		(property "Device Type" "R402H16"
			(at 0.064008 -5.517896 90)
			(unlocked yes)
			(layer "F.Fab")
			(hide yes)
			(effects
				(font
					(size 1.016 1.016)
					(thickness 0.1524)
				)
			)
		)
		(duplicate_pad_numbers_are_jumpers no)
		(fp_line
			(start 0.508 -0.9398)
			(end -0.508 -0.9398)
			(stroke
				(width 0.1524)
				(type default)
			)
			(layer "F.SilkS")
		)
		(fp_line
			(start -0.508 -0.9398)
			(end -0.508 0.9398)
			(stroke
				(width 0.1524)
				(type default)
			)
			(layer "F.SilkS")
		)
		(fp_rect
			(start -0.508 0.9398)
			(end 0.508 -0.9398)
			(stroke
				(width 0)
				(type default)
			)
			(fill no)
			(layer "F.CrtYd")
		)
		(fp_rect
			(start -0.508 0.9398)
			(end 0.508 -0.9398)
			(stroke
				(width 0)
				(type default)
			)
			(fill no)
			(layer "F.Fab")
		)
		(pad "1" smd custom
			(at 0 -0.4445 90)
			(size 0.1397 0.1397)
			(layers "F.Cu" "F.Mask" "F.Paste")
			(net "P3V3_STBY_VO")
			(options
				(clearance outline)
				(anchor circle)
			)
			(primitives
				(gr_poly
					(pts
						(arc
							(start -0.1778 -0.2794)
							(mid -0.249642 -0.249642)
							(end -0.2794 -0.1778)
						)
						(arc
							(start -0.2794 0.1778)
							(mid -0.249642 0.249642)
							(end -0.1778 0.2794)
						)
						(arc
							(start 0.1778 0.2794)
							(mid 0.249642 0.249642)
							(end 0.2794 0.1778)
						)
						(arc
							(start 0.2794 -0.1778)
							(mid 0.249642 -0.249642)
							(end 0.1778 -0.2794)
						)
					)
					(width 0)
					(fill yes)
				)
			)
		)
		(pad "2" smd custom
			(at 0 0.4445 90)
			(size 0.1397 0.1397)
			(layers "F.Cu" "F.Mask" "F.Paste")
			(net "P3V3_STBY_CC_R")
			(options
				(clearance outline)
				(anchor circle)
			)
			(primitives
				(gr_poly
					(pts
						(arc
							(start -0.1778 -0.2794)
							(mid -0.249642 -0.249642)
							(end -0.2794 -0.1778)
						)
						(arc
							(start -0.2794 0.1778)
							(mid -0.249642 0.249642)
							(end -0.1778 0.2794)
						)
						(arc
							(start 0.1778 0.2794)
							(mid 0.249642 0.249642)
							(end 0.2794 0.1778)
						)
						(arc
							(start 0.2794 -0.1778)
							(mid 0.249642 -0.249642)
							(end 0.1778 -0.2794)
						)
					)
					(width 0)
					(fill yes)
				)
			)
		)
	)
	(footprint ""
		(layer "F.Cu")
		(at 109.855 -248.158 180)
		(property "Reference" "R218"
			(at 0 0 180)
			(layer "F.SilkS")
			(hide yes)
			(effects
				(font
					(size 1.27 1.27)
				)
			)
		)
		(property "Value" "200KR2F-L-GP"
			(at 0.064008 -3.993896 180)
			(unlocked yes)
			(layer "F.Fab")
			(hide yes)
			(effects
				(font
					(size 1.016 1.016)
					(thickness 0.1524)
				)
			)
		)
		(property "Device Type" "R402H16"
			(at 0.064008 -5.517896 180)
			(unlocked yes)
			(layer "F.Fab")
			(hide yes)
			(effects
				(font
					(size 1.016 1.016)
					(thickness 0.1524)
				)
			)
		)
		(duplicate_pad_numbers_are_jumpers no)
		(fp_line
			(start 0.508 -0.9398)
			(end -0.508 -0.9398)
			(stroke
				(width 0.1524)
				(type default)
			)
			(layer "F.SilkS")
		)
		(fp_line
			(start -0.508 -0.9398)
			(end -0.508 0.9398)
			(stroke
				(width 0.1524)
				(type default)
			)
			(layer "F.SilkS")
		)
		(fp_rect
			(start -0.508 0.9398)
			(end 0.508 -0.9398)
			(stroke
				(width 0)
				(type default)
			)
			(fill no)
			(layer "F.CrtYd")
		)
		(fp_rect
			(start -0.508 0.9398)
			(end 0.508 -0.9398)
			(stroke
				(width 0)
				(type default)
			)
			(fill no)
			(layer "F.Fab")
		)
		(pad "1" smd custom
			(at 0 -0.4445 180)
			(size 0.1397 0.1397)
			(layers "F.Cu" "F.Mask" "F.Paste")
			(net "SW_HDD_R3")
			(options
				(clearance outline)
				(anchor circle)
			)
			(primitives
				(gr_poly
					(pts
						(arc
							(start -0.1778 -0.2794)
							(mid -0.249642 -0.249642)
							(end -0.2794 -0.1778)
						)
						(arc
							(start -0.2794 0.1778)
							(mid -0.249642 0.249642)
							(end -0.1778 0.2794)
						)
						(arc
							(start 0.1778 0.2794)
							(mid 0.249642 0.249642)
							(end 0.2794 0.1778)
						)
						(arc
							(start 0.2794 -0.1778)
							(mid 0.249642 -0.249642)
							(end 0.1778 -0.2794)
						)
					)
					(width 0)
					(fill yes)
				)
			)
		)
		(pad "2" smd custom
			(at 0 0.4445 180)
			(size 0.1397 0.1397)
			(layers "F.Cu" "F.Mask" "F.Paste")
			(net "SW_HDD_N3")
			(options
				(clearance outline)
				(anchor circle)
			)
			(primitives
				(gr_poly
					(pts
						(arc
							(start -0.1778 -0.2794)
							(mid -0.249642 -0.249642)
							(end -0.2794 -0.1778)
						)
						(arc
							(start -0.2794 0.1778)
							(mid -0.249642 0.249642)
							(end -0.1778 0.2794)
						)
						(arc
							(start 0.1778 0.2794)
							(mid 0.249642 0.249642)
							(end 0.2794 0.1778)
						)
						(arc
							(start 0.2794 -0.1778)
							(mid 0.249642 -0.249642)
							(end 0.1778 -0.2794)
						)
					)
					(width 0)
					(fill yes)
				)
			)
		)
	)
)
